# T6G (Grand Teton) — schematic netlist excerpt (pin names and nets, part order shuffled) for the footprints in the layout excerpt that follows; sources: Cadence DE-HDL packaged netlist, KiCad conversion of 04192023_DAF0TMB3IC0_F0TG_MB_C_brd_V02_OCP.brd

PC6562  Q_CAP  0.1UF 25V 10% X7R  pkg 0402  page 363 : A = P12V_AUX ; B = GND
R6796  Q_RES  0 5% CHIP  pkg 0201LF  page 343 : A = NCF_A1_CPU1_P2_GND ; B = GND
PC524  Q_CAP  100NF 50V 10% X7R  pkg C0402  page 225 : A = PVDD11_S3_P1 ; B = GND

(kicad_pcb
	(version 20260206)
	(generator "pcbnew")
	(generator_version "10.0")
	(general
		(thickness 1.6)
		(legacy_teardrops no)
	)
	(paper "A4")
	(title_block
		(title "04192023_DAF0TMB3IC0_F0TG_MB_C_brd_V02_OCP.brd")
		(comment 1 "Grand Teton / footprints 4215-4217 of 8354")
	)
	(layers
		(0 "F.Cu" signal "TOP")
		(4 "In1.Cu" signal "GND")
		(6 "In2.Cu" signal "IN1")
		(8 "In3.Cu" signal "GND1")
		(10 "In4.Cu" signal "IN2")
		(12 "In5.Cu" signal "GND2")
		(14 "In6.Cu" signal "IN3")
		(16 "In7.Cu" signal "GND3")
		(18 "In8.Cu" signal "VCC")
		(20 "In9.Cu" signal "VCC1")
		(22 "In10.Cu" signal "GND4")
		(24 "In11.Cu" signal "IN4")
		(26 "In12.Cu" signal "GND5")
		(28 "In13.Cu" signal "IN5")
		(30 "In14.Cu" signal "GND6")
		(32 "In15.Cu" signal "IN6")
		(34 "In16.Cu" signal "GND7")
		(2 "B.Cu" signal "BOTTOM")
		(9 "F.Adhes" user "F.Adhesive")
		(11 "B.Adhes" user "B.Adhesive")
		(13 "F.Paste" user "Package Geometry/Pastemask Top")
		(15 "B.Paste" user "Package Geometry/Pastemask Bottom")
		(5 "F.SilkS" user "Ref Des/Silkscreen Top")
		(7 "B.SilkS" user "Ref Des/Silkscreen Bottom")
		(1 "F.Mask" user "Board Geometry/Soldermask Top")
		(3 "B.Mask" user "Board Geometry/Soldermask Bottom")
		(17 "Dwgs.User" user "User.Drawings")
		(19 "Cmts.User" user "User.Comments")
		(21 "Eco1.User" user "User.Eco1")
		(23 "Eco2.User" user "User.Eco2")
		(25 "Edge.Cuts" user "Board Geometry/Outline")
		(27 "Margin" user)
		(31 "F.CrtYd" user "Package Geometry/Place Bound Top")
		(29 "B.CrtYd" user "Package Geometry/Place Bound Bottom")
		(35 "F.Fab" user "Ref Des/Assembly Top")
		(33 "B.Fab" user "Ref Des/Assembly Bottom")
	)
	(footprint ""
		(layer "F.Cu")
		(at 448.671442 -415.464244 180)
		(property "Reference" "PC6562"
			(at 0 0 180)
			(layer "F.SilkS")
			(hide yes)
			(effects
				(font
					(size 1.27 1.27)
				)
			)
		)
		(property "Value" ""
			(at 0 0 180)
			(layer "F.Fab")
			(effects
				(font
					(size 1.27 1.27)
				)
			)
		)
		(duplicate_pad_numbers_are_jumpers no)
		(fp_line
			(start 0.7874 0.4064)
			(end -0.7874 0.4064)
			(stroke
				(width 0.1524)
				(type default)
			)
			(layer "F.SilkS")
		)
		(fp_line
			(start 0.7874 -0.4064)
			(end 0.7874 0.4064)
			(stroke
				(width 0.1524)
				(type default)
			)
			(layer "F.SilkS")
		)
		(fp_line
			(start -0.7874 0.4064)
			(end -0.7874 -0.4064)
			(stroke
				(width 0.1524)
				(type default)
			)
			(layer "F.SilkS")
		)
		(fp_line
			(start -0.7874 -0.4064)
			(end 0.7874 -0.4064)
			(stroke
				(width 0.1524)
				(type default)
			)
			(layer "F.SilkS")
		)
		(fp_line
			(start 0.67945 0.3048)
			(end 0.120396 0.3048)
			(stroke
				(width 0.1)
				(type default)
			)
			(layer "F.Fab")
		)
		(fp_line
			(start 0.67945 -0.3048)
			(end 0.67945 0.3048)
			(stroke
				(width 0.1)
				(type default)
			)
			(layer "F.Fab")
		)
		(fp_line
			(start 0.12065 -0.2794)
			(end 0.12065 -0.3048)
			(stroke
				(width 0.1)
				(type default)
			)
			(layer "F.Fab")
		)
		(fp_line
			(start 0.12065 -0.3048)
			(end 0.67945 -0.3048)
			(stroke
				(width 0.1)
				(type default)
			)
			(layer "F.Fab")
		)
		(fp_line
			(start 0.120396 0.3048)
			(end 0.120396 0.2794)
			(stroke
				(width 0.1)
				(type default)
			)
			(layer "F.Fab")
		)
		(fp_line
			(start 0.120396 0.2794)
			(end -0.12065 0.2794)
			(stroke
				(width 0.1)
				(type default)
			)
			(layer "F.Fab")
		)
		(fp_line
			(start -0.12065 0.3048)
			(end -0.67945 0.3048)
			(stroke
				(width 0.1)
				(type default)
			)
			(layer "F.Fab")
		)
		(fp_line
			(start -0.12065 0.2794)
			(end -0.12065 0.3048)
			(stroke
				(width 0.1)
				(type default)
			)
			(layer "F.Fab")
		)
		(fp_line
			(start -0.12065 -0.2794)
			(end 0.12065 -0.2794)
			(stroke
				(width 0.1)
				(type default)
			)
			(layer "F.Fab")
		)
		(fp_line
			(start -0.12065 -0.305054)
			(end -0.12065 -0.2794)
			(stroke
				(width 0.1)
				(type default)
			)
			(layer "F.Fab")
		)
		(fp_line
			(start -0.67945 0.3048)
			(end -0.67945 -0.305054)
			(stroke
				(width 0.1)
				(type default)
			)
			(layer "F.Fab")
		)
		(fp_line
			(start -0.67945 -0.305054)
			(end -0.12065 -0.305054)
			(stroke
				(width 0.1)
				(type default)
			)
			(layer "F.Fab")
		)
		(pad "1" smd circle
			(at -0.40005 0 180)
			(size 0 0)
			(layers "F.Cu" "F.Mask" "F.Paste")
			(net "P12V_AUX")
		)
		(pad "2" smd circle
			(at 0.40005 0 180)
			(size 0 0)
			(layers "F.Cu" "F.Mask" "F.Paste")
			(net "GND")
		)
	)
	(footprint ""
		(layer "F.Cu")
		(at 172.230034 -332.788006 -90)
		(property "Reference" "PC524"
			(at 0 0 270)
			(layer "F.SilkS")
			(hide yes)
			(effects
				(font
					(size 1.27 1.27)
				)
			)
		)
		(property "Value" ""
			(at 0 0 270)
			(layer "F.Fab")
			(effects
				(font
					(size 1.27 1.27)
				)
			)
		)
		(duplicate_pad_numbers_are_jumpers no)
		(fp_line
			(start -0.7874 0.4064)
			(end -0.7874 -0.4064)
			(stroke
				(width 0.1524)
				(type default)
			)
			(layer "F.SilkS")
		)
		(fp_line
			(start 0.7874 0.4064)
			(end -0.7874 0.4064)
			(stroke
				(width 0.1524)
				(type default)
			)
			(layer "F.SilkS")
		)
		(fp_line
			(start -0.7874 -0.4064)
			(end 0.7874 -0.4064)
			(stroke
				(width 0.1524)
				(type default)
			)
			(layer "F.SilkS")
		)
		(fp_line
			(start 0.7874 -0.4064)
			(end 0.7874 0.4064)
			(stroke
				(width 0.1524)
				(type default)
			)
			(layer "F.SilkS")
		)
		(fp_line
			(start -0.67945 0.3048)
			(end -0.67945 -0.305054)
			(stroke
				(width 0.1)
				(type default)
			)
			(layer "F.Fab")
		)
		(fp_line
			(start -0.12065 0.3048)
			(end -0.67945 0.3048)
			(stroke
				(width 0.1)
				(type default)
			)
			(layer "F.Fab")
		)
		(fp_line
			(start 0.120396 0.3048)
			(end 0.120396 0.2794)
			(stroke
				(width 0.1)
				(type default)
			)
			(layer "F.Fab")
		)
		(fp_line
			(start 0.67945 0.3048)
			(end 0.120396 0.3048)
			(stroke
				(width 0.1)
				(type default)
			)
			(layer "F.Fab")
		)
		(fp_line
			(start -0.12065 0.2794)
			(end -0.12065 0.3048)
			(stroke
				(width 0.1)
				(type default)
			)
			(layer "F.Fab")
		)
		(fp_line
			(start 0.120396 0.2794)
			(end -0.12065 0.2794)
			(stroke
				(width 0.1)
				(type default)
			)
			(layer "F.Fab")
		)
		(fp_line
			(start -0.12065 -0.2794)
			(end 0.12065 -0.2794)
			(stroke
				(width 0.1)
				(type default)
			)
			(layer "F.Fab")
		)
		(fp_line
			(start 0.12065 -0.2794)
			(end 0.12065 -0.3048)
			(stroke
				(width 0.1)
				(type default)
			)
			(layer "F.Fab")
		)
		(fp_line
			(start 0.12065 -0.3048)
			(end 0.67945 -0.3048)
			(stroke
				(width 0.1)
				(type default)
			)
			(layer "F.Fab")
		)
		(fp_line
			(start 0.67945 -0.3048)
			(end 0.67945 0.3048)
			(stroke
				(width 0.1)
				(type default)
			)
			(layer "F.Fab")
		)
		(fp_line
			(start -0.67945 -0.305054)
			(end -0.12065 -0.305054)
			(stroke
				(width 0.1)
				(type default)
			)
			(layer "F.Fab")
		)
		(fp_line
			(start -0.12065 -0.305054)
			(end -0.12065 -0.2794)
			(stroke
				(width 0.1)
				(type default)
			)
			(layer "F.Fab")
		)
		(pad "1" smd circle
			(at -0.40005 0 270)
			(size 0 0)
			(layers "F.Cu" "F.Mask" "F.Paste")
			(net "PVDD11_S3_P1")
		)
		(pad "2" smd circle
			(at 0.40005 0 270)
			(size 0 0)
			(layers "F.Cu" "F.Mask" "F.Paste")
			(net "GND")
		)
	)
	(footprint ""
		(layer "F.Cu")
		(at 168.60901 -394.3604 -90)
		(property "Reference" "R6796"
			(at 0 0 270)
			(layer "F.SilkS")
			(hide yes)
			(effects
				(font
					(size 1.27 1.27)
				)
			)
		)
		(property "Value" ""
			(at 0 0 270)
			(layer "F.Fab")
			(effects
				(font
					(size 1.27 1.27)
				)
			)
		)
		(duplicate_pad_numbers_are_jumpers no)
		(fp_line
			(start -0.32512 0.175006)
			(end -0.32512 -0.175006)
			(stroke
				(width 0.1)
				(type default)
			)
			(layer "F.Fab")
		)
		(fp_line
			(start 0.32512 0.175006)
			(end -0.32512 0.175006)
			(stroke
				(width 0.1)
				(type default)
			)
			(layer "F.Fab")
		)
		(fp_line
			(start -0.32512 -0.175006)
			(end 0.32512 -0.175006)
			(stroke
				(width 0.1)
				(type default)
			)
			(layer "F.Fab")
		)
		(fp_line
			(start 0.32512 -0.175006)
			(end 0.32512 0.175006)
			(stroke
				(width 0.1)
				(type default)
			)
			(layer "F.Fab")
		)
		(pad "1" smd rect
			(at -0.2667 0 270)
			(size 0.3048 0.381)
			(layers "F.Cu" "F.Mask" "F.Paste")
			(net "NCF_A1_CPU1_P2_GND")
		)
		(pad "2" smd rect
			(at 0.2667 0 90)
			(size 0.3048 0.381)
			(layers "F.Cu" "F.Mask" "F.Paste")
			(net "GND")
		)
	)
)
